(kicad_pcb
	(version 20260206)
	(generator "pcbnew")
	(generator_version "10.0")
	(general
		(thickness 1.6)
		(legacy_teardrops no)
	)
	(paper "A4")
	(title_block
		(title "Wiwynn_Tioga_Pass_MB.brd")
		(comment 1 "Tioga Pass / footprints 2822-2829 of 4770")
	)
	(layers
		(0 "F.Cu" signal "TOP")
		(4 "In1.Cu" signal "L2GND")
		(6 "In2.Cu" signal "L3")
		(8 "In3.Cu" signal "L4GND")
		(10 "In4.Cu" signal "L5")
		(12 "In5.Cu" signal "L6GND")
		(14 "In6.Cu" signal "L7VCC")
		(16 "In7.Cu" signal "L8VCC")
		(18 "In8.Cu" signal "L9GND")
		(20 "In9.Cu" signal "L10")
		(22 "In10.Cu" signal "L11GND")
		(24 "In11.Cu" signal "L12")
		(26 "In12.Cu" signal "L13GND")
		(2 "B.Cu" signal "BOTTOM")
		(9 "F.Adhes" user "F.Adhesive")
		(11 "B.Adhes" user "B.Adhesive")
		(13 "F.Paste" user "Package Geometry/Pastemask Top")
		(15 "B.Paste" user "Package Geometry/Pastemask Bottom")
		(5 "F.SilkS" user "Ref Des/Silkscreen Top")
		(7 "B.SilkS" user "Ref Des/Silkscreen Bottom")
		(1 "F.Mask" user "Board Geometry/Soldermask Top")
		(3 "B.Mask" user "Board Geometry/Soldermask Bottom")
		(17 "Dwgs.User" user "User.Drawings")
		(19 "Cmts.User" user "User.Comments")
		(21 "Eco1.User" user "User.Eco1")
		(23 "Eco2.User" user "User.Eco2")
		(25 "Edge.Cuts" user "Board Geometry/Outline")
		(27 "Margin" user)
		(31 "F.CrtYd" user "Package Geometry/Place Bound Top")
		(29 "B.CrtYd" user "Package Geometry/Place Bound Bottom")
		(35 "F.Fab" user "Ref Des/Assembly Top")
		(33 "B.Fab" user "Ref Des/Assembly Bottom")
	)
	(footprint ""
		(layer "B.Cu")
		(at 193.675 -154.559 180)
		(property "Reference" "R6L2"
			(at 0 0 0)
			(layer "B.SilkS")
			(hide yes)
			(effects
				(font
					(size 1.27 1.27)
				)
				(justify mirror)
			)
		)
		(property "Value" ""
			(at 0 0 0)
			(layer "B.Fab")
			(effects
				(font
					(size 1.27 1.27)
				)
				(justify mirror)
			)
		)
		(duplicate_pad_numbers_are_jumpers no)
		(fp_poly
			(pts
				(xy 0.2794 -0.1016) (xy -0.2794 -0.1016) (xy -0.2794 0.9906) (xy 0.2794 0.9906)
			)
			(stroke
				(width 0)
				(type default)
			)
			(fill no)
			(layer "B.CrtYd")
		)
		(fp_line
			(start 0.2794 0.9906)
			(end -0.2794 0.9906)
			(stroke
				(width 0.1)
				(type default)
			)
			(layer "B.Fab")
		)
		(fp_line
			(start 0.2794 -0.1016)
			(end 0.2794 0.9906)
			(stroke
				(width 0.1)
				(type default)
			)
			(layer "B.Fab")
		)
		(fp_line
			(start -0.2794 0.9906)
			(end -0.2794 -0.1016)
			(stroke
				(width 0.1)
				(type default)
			)
			(layer "B.Fab")
		)
		(fp_line
			(start -0.2794 -0.1016)
			(end 0.2794 -0.1016)
			(stroke
				(width 0.1)
				(type default)
			)
			(layer "B.Fab")
		)
		(pad "1" smd rect
			(at 0 0)
			(size 0.508 0.508)
			(layers "B.Cu" "B.Mask" "B.Paste")
			(net "PVDDQ_DEF")
		)
		(pad "2" smd rect
			(at 0 0.889)
			(size 0.508 0.508)
			(layers "B.Cu" "B.Mask" "B.Paste")
			(net "M_F_VREF")
		)
		(zone
			(layer "B.Cu")
			(hatch none 0.5)
			(connect_pads
				(clearance 0)
			)
			(min_thickness 0.25)
			(keepout
				(tracks not_allowed)
				(vias allowed)
				(pads allowed)
				(copperpour not_allowed)
				(footprints allowed)
			)
			(placement
				(enabled no)
				(sheetname "")
			)
			(fill
				(thermal_gap 0.5)
				(thermal_bridge_width 0.5)
				(island_removal_mode 0)
			)
			(polygon
				(pts
					(xy 193.421 -155.194) (xy 193.929 -155.194) (xy 193.929 -154.813) (xy 193.421 -154.813)
				)
			)
		)
		(zone
			(layer "B.Cu")
			(hatch none 0.5)
			(connect_pads
				(clearance 0)
			)
			(min_thickness 0.25)
			(keepout
				(tracks allowed)
				(vias not_allowed)
				(pads allowed)
				(copperpour not_allowed)
				(footprints allowed)
			)
			(placement
				(enabled no)
				(sheetname "")
			)
			(fill
				(thermal_gap 0.5)
				(thermal_bridge_width 0.5)
				(island_removal_mode 0)
			)
			(polygon
				(pts
					(xy 193.421 -154.813) (xy 193.929 -154.813) (xy 193.929 -155.194) (xy 193.421 -155.194)
				)
			)
		)
	)
	(footprint ""
		(layer "B.Cu")
		(at 378.1298 -133.9088 -90)
		(property "Reference" "C3M23"
			(at 0 0 90)
			(layer "B.SilkS")
			(hide yes)
			(effects
				(font
					(size 1.27 1.27)
				)
				(justify mirror)
			)
		)
		(property "Value" ""
			(at 0 0 90)
			(layer "B.Fab")
			(effects
				(font
					(size 1.27 1.27)
				)
				(justify mirror)
			)
		)
		(duplicate_pad_numbers_are_jumpers no)
		(fp_poly
			(pts
				(xy 0.4953 -0.2032) (xy -0.4953 -0.2032) (xy -0.4953 1.6002) (xy 0.4953 1.6002)
			)
			(stroke
				(width 0)
				(type default)
			)
			(fill no)
			(layer "B.CrtYd")
		)
		(fp_line
			(start -0.4953 1.6002)
			(end 0.4953 1.6002)
			(stroke
				(width 0.1)
				(type default)
			)
			(layer "B.Fab")
		)
		(fp_line
			(start 0.4953 1.6002)
			(end 0.4953 -0.2032)
			(stroke
				(width 0.1)
				(type default)
			)
			(layer "B.Fab")
		)
		(fp_line
			(start -0.4953 -0.2032)
			(end -0.4953 1.6002)
			(stroke
				(width 0.1)
				(type default)
			)
			(layer "B.Fab")
		)
		(fp_line
			(start 0.4953 -0.2032)
			(end -0.4953 -0.2032)
			(stroke
				(width 0.1)
				(type default)
			)
			(layer "B.Fab")
		)
		(pad "1" smd rect
			(at 0 0 90)
			(size 0.762 0.889)
			(layers "B.Cu" "B.Mask" "B.Paste")
			(net "P1V05_PCH_STBY_VCCA_XTAL")
		)
		(pad "2" smd rect
			(at 0 1.397 90)
			(size 0.762 0.889)
			(layers "B.Cu" "B.Mask" "B.Paste")
			(net "GND")
		)
		(zone
			(layer "B.Cu")
			(hatch none 0.5)
			(connect_pads
				(clearance 0)
			)
			(min_thickness 0.25)
			(keepout
				(tracks not_allowed)
				(vias allowed)
				(pads allowed)
				(copperpour not_allowed)
				(footprints allowed)
			)
			(placement
				(enabled no)
				(sheetname "")
			)
			(fill
				(thermal_gap 0.5)
				(thermal_bridge_width 0.5)
				(island_removal_mode 0)
			)
			(polygon
				(pts
					(xy 377.6853 -133.5278) (xy 377.6853 -134.2898) (xy 377.1773 -134.2898) (xy 377.1773 -133.5278)
				)
			)
		)
	)
	(footprint ""
		(layer "B.Cu")
		(at 83.856068 -149.8092 -90)
		(property "Reference" "C5G100"
			(at -1.14681 0.76708 0)
			(unlocked yes)
			(layer "B.SilkS")
			(effects
				(font
					(size 0.7874 0.5842)
					(thickness 0.1524)
				)
				(justify mirror)
			)
		)
		(property "Value" ""
			(at 0 0 90)
			(layer "B.Fab")
			(effects
				(font
					(size 1.27 1.27)
				)
				(justify mirror)
			)
		)
		(duplicate_pad_numbers_are_jumpers no)
		(fp_rect
			(start 0.4953 1.6002)
			(end -0.4953 -0.2032)
			(stroke
				(width 0)
				(type default)
			)
			(fill no)
			(layer "B.CrtYd")
		)
		(fp_line
			(start -0.4953 1.6002)
			(end 0.4953 1.6002)
			(stroke
				(width 0.1)
				(type default)
			)
			(layer "B.Fab")
		)
		(fp_line
			(start 0.4953 1.6002)
			(end 0.4953 -0.2032)
			(stroke
				(width 0.1)
				(type default)
			)
			(layer "B.Fab")
		)
		(fp_line
			(start -0.4953 -0.2032)
			(end -0.4953 1.6002)
			(stroke
				(width 0.1)
				(type default)
			)
			(layer "B.Fab")
		)
		(fp_line
			(start 0.4953 -0.2032)
			(end -0.4953 -0.2032)
			(stroke
				(width 0.1)
				(type default)
			)
			(layer "B.Fab")
		)
		(pad "1" smd rect
			(at 0 0 90)
			(size 0.762 0.889)
			(layers "B.Cu" "B.Mask" "B.Paste")
			(net "PVDDQ_KLM")
		)
		(pad "2" smd rect
			(at 0 1.397 90)
			(size 0.762 0.889)
			(layers "B.Cu" "B.Mask" "B.Paste")
			(net "GND")
		)
		(zone
			(layer "B.Cu")
			(hatch none 0.5)
			(connect_pads
				(clearance 0)
			)
			(min_thickness 0.25)
			(keepout
				(tracks not_allowed)
				(vias allowed)
				(pads allowed)
				(copperpour not_allowed)
				(footprints allowed)
			)
			(placement
				(enabled no)
				(sheetname "")
			)
			(fill
				(thermal_gap 0.5)
				(thermal_bridge_width 0.5)
				(island_removal_mode 0)
			)
			(polygon
				(pts
					(xy 82.903568 -149.4282) (xy 83.411568 -149.4282) (xy 83.411568 -150.1902) (xy 82.903568 -150.1902)
				)
			)
		)
	)
	(footprint ""
		(layer "B.Cu")
		(at 467.868 -46.6725 180)
		(property "Reference" "R9E11"
			(at 0 0 0)
			(layer "B.SilkS")
			(hide yes)
			(effects
				(font
					(size 1.27 1.27)
				)
				(justify mirror)
			)
		)
		(property "Value" ""
			(at 0 0 0)
			(layer "B.Fab")
			(effects
				(font
					(size 1.27 1.27)
				)
				(justify mirror)
			)
		)
		(duplicate_pad_numbers_are_jumpers no)
		(fp_poly
			(pts
				(xy 0.2794 -0.1016) (xy -0.2794 -0.1016) (xy -0.2794 0.9906) (xy 0.2794 0.9906)
			)
			(stroke
				(width 0)
				(type default)
			)
			(fill no)
			(layer "B.CrtYd")
		)
		(fp_line
			(start 0.2794 0.9906)
			(end -0.2794 0.9906)
			(stroke
				(width 0.1)
				(type default)
			)
			(layer "B.Fab")
		)
		(fp_line
			(start 0.2794 -0.1016)
			(end 0.2794 0.9906)
			(stroke
				(width 0.1)
				(type default)
			)
			(layer "B.Fab")
		)
		(fp_line
			(start -0.2794 0.9906)
			(end -0.2794 -0.1016)
			(stroke
				(width 0.1)
				(type default)
			)
			(layer "B.Fab")
		)
		(fp_line
			(start -0.2794 -0.1016)
			(end 0.2794 -0.1016)
			(stroke
				(width 0.1)
				(type default)
			)
			(layer "B.Fab")
		)
		(pad "1" smd rect
			(at 0 0)
			(size 0.508 0.508)
			(layers "B.Cu" "B.Mask" "B.Paste")
			(net "RST_PCIE_CPU_DEV2_R_N")
		)
		(pad "2" smd rect
			(at 0 0.889)
			(size 0.508 0.508)
			(layers "B.Cu" "B.Mask" "B.Paste")
			(net "RST_PCIE_CPU_DEV2_N")
		)
		(zone
			(layer "B.Cu")
			(hatch none 0.5)
			(connect_pads
				(clearance 0)
			)
			(min_thickness 0.25)
			(keepout
				(tracks not_allowed)
				(vias allowed)
				(pads allowed)
				(copperpour not_allowed)
				(footprints allowed)
			)
			(placement
				(enabled no)
				(sheetname "")
			)
			(fill
				(thermal_gap 0.5)
				(thermal_bridge_width 0.5)
				(island_removal_mode 0)
			)
			(polygon
				(pts
					(xy 467.614 -47.3075) (xy 468.122 -47.3075) (xy 468.122 -46.9265) (xy 467.614 -46.9265)
				)
			)
		)
		(zone
			(layer "B.Cu")
			(hatch none 0.5)
			(connect_pads
				(clearance 0)
			)
			(min_thickness 0.25)
			(keepout
				(tracks allowed)
				(vias not_allowed)
				(pads allowed)
				(copperpour not_allowed)
				(footprints allowed)
			)
			(placement
				(enabled no)
				(sheetname "")
			)
			(fill
				(thermal_gap 0.5)
				(thermal_bridge_width 0.5)
				(island_removal_mode 0)
			)
			(polygon
				(pts
					(xy 467.614 -46.9265) (xy 468.122 -46.9265) (xy 468.122 -47.3075) (xy 467.614 -47.3075)
				)
			)
		)
	)
	(footprint ""
		(layer "B.Cu")
		(at 197.848728 -60.079382 90)
		(property "Reference" "C6R6"
			(at 0 0 90)
			(layer "B.SilkS")
			(hide yes)
			(effects
				(font
					(size 1.27 1.27)
				)
				(justify mirror)
			)
		)
		(property "Value" ""
			(at 0 0 90)
			(layer "B.Fab")
			(effects
				(font
					(size 1.27 1.27)
				)
				(justify mirror)
			)
		)
		(duplicate_pad_numbers_are_jumpers no)
		(fp_rect
			(start -0.7239 -0.2159)
			(end 0.7239 1.9939)
			(stroke
				(width 0)
				(type default)
			)
			(fill no)
			(layer "B.CrtYd")
		)
		(fp_line
			(start 0.7239 -0.2159)
			(end 0.7239 1.9939)
			(stroke
				(width 0.1)
				(type default)
			)
			(layer "B.Fab")
		)
		(fp_line
			(start -0.7239 -0.2159)
			(end 0.7239 -0.2159)
			(stroke
				(width 0.1)
				(type default)
			)
			(layer "B.Fab")
		)
		(fp_line
			(start 0.7239 1.9939)
			(end -0.7239 1.9939)
			(stroke
				(width 0.1)
				(type default)
			)
			(layer "B.Fab")
		)
		(fp_line
			(start -0.7239 1.9939)
			(end -0.7239 -0.2159)
			(stroke
				(width 0.1)
				(type default)
			)
			(layer "B.Fab")
		)
		(pad "1" smd rect
			(at 0 0 270)
			(size 1.27 1.016)
			(layers "B.Cu" "B.Mask" "B.Paste")
			(net "VR_FET_SW_P12V_STBY_PVCCIN_CPU0")
		)
		(pad "2" smd rect
			(at 0 1.778 270)
			(size 1.27 1.016)
			(layers "B.Cu" "B.Mask" "B.Paste")
			(net "GND")
		)
		(zone
			(layer "B.Cu")
			(hatch none 0.5)
			(connect_pads
				(clearance 0)
			)
			(min_thickness 0.25)
			(keepout
				(tracks not_allowed)
				(vias allowed)
				(pads allowed)
				(copperpour not_allowed)
				(footprints allowed)
			)
			(placement
				(enabled no)
				(sheetname "")
			)
			(fill
				(thermal_gap 0.5)
				(thermal_bridge_width 0.5)
				(island_removal_mode 0)
			)
			(polygon
				(pts
					(xy 198.356728 -59.444382) (xy 199.118728 -59.444382) (xy 199.118728 -60.714382) (xy 198.356728 -60.714382)
				)
			)
		)
	)
	(footprint ""
		(layer "B.Cu")
		(at 340.16696 -77.694536)
		(property "Reference" "C3P12"
			(at 0 0 0)
			(layer "B.SilkS")
			(hide yes)
			(effects
				(font
					(size 1.27 1.27)
				)
				(justify mirror)
			)
		)
		(property "Value" ""
			(at 0 0 0)
			(layer "B.Fab")
			(effects
				(font
					(size 1.27 1.27)
				)
				(justify mirror)
			)
		)
		(duplicate_pad_numbers_are_jumpers no)
		(fp_poly
			(pts
				(xy -0.3048 -0.1016) (xy -0.3048 0.9906) (xy 0.3048 0.9906) (xy 0.3048 -0.1016)
			)
			(stroke
				(width 0)
				(type default)
			)
			(fill no)
			(layer "B.CrtYd")
		)
		(fp_line
			(start -0.3048 -0.1016)
			(end 0.3048 -0.1016)
			(stroke
				(width 0.1)
				(type default)
			)
			(layer "B.Fab")
		)
		(fp_line
			(start -0.3048 0.9906)
			(end -0.3048 -0.1016)
			(stroke
				(width 0.1)
				(type default)
			)
			(layer "B.Fab")
		)
		(fp_line
			(start 0.3048 -0.1016)
			(end 0.3048 0.9906)
			(stroke
				(width 0.1)
				(type default)
			)
			(layer "B.Fab")
		)
		(fp_line
			(start 0.3048 0.9906)
			(end -0.3048 0.9906)
			(stroke
				(width 0.1)
				(type default)
			)
			(layer "B.Fab")
		)
		(pad "1" smd rect
			(at 0 0 180)
			(size 0.508 0.508)
			(layers "B.Cu" "B.Mask" "B.Paste")
			(net "P3E_CPU0_PE1_SS_TXN<0>")
		)
		(pad "2" smd rect
			(at 0 0.889 180)
			(size 0.508 0.508)
			(layers "B.Cu" "B.Mask" "B.Paste")
			(net "P3E_CPU0_PE1_SS_C_TXN<0>")
		)
		(zone
			(layer "B.Cu")
			(hatch none 0.5)
			(connect_pads
				(clearance 0)
			)
			(min_thickness 0.25)
			(keepout
				(tracks allowed)
				(vias not_allowed)
				(pads allowed)
				(copperpour not_allowed)
				(footprints allowed)
			)
			(placement
				(enabled no)
				(sheetname "")
			)
			(fill
				(thermal_gap 0.5)
				(thermal_bridge_width 0.5)
				(island_removal_mode 0)
			)
			(polygon
				(pts
					(xy 340.42096 -77.440536) (xy 339.91296 -77.440536) (xy 339.91296 -77.059536) (xy 340.42096 -77.059536)
				)
			)
		)
		(zone
			(layer "B.Cu")
			(hatch none 0.5)
			(connect_pads
				(clearance 0)
			)
			(min_thickness 0.25)
			(keepout
				(tracks not_allowed)
				(vias allowed)
				(pads allowed)
				(copperpour not_allowed)
				(footprints allowed)
			)
			(placement
				(enabled no)
				(sheetname "")
			)
			(fill
				(thermal_gap 0.5)
				(thermal_bridge_width 0.5)
				(island_removal_mode 0)
			)
			(polygon
				(pts
					(xy 340.42096 -77.059536) (xy 339.91296 -77.059536) (xy 339.91296 -77.440536) (xy 340.42096 -77.440536)
				)
			)
		)
	)
	(footprint ""
		(layer "B.Cu")
		(at 476.174816 -146.359372)
		(property "Reference" "R6W6"
			(at 0.8382 -0.67818 0)
			(unlocked yes)
			(layer "B.SilkS")
			(effects
				(font
					(size 0.4064 0.254)
					(thickness 0.1524)
				)
				(justify left mirror)
			)
		)
		(property "Value" ""
			(at 0 0 0)
			(layer "B.Fab")
			(effects
				(font
					(size 1.27 1.27)
				)
				(justify mirror)
			)
		)
		(duplicate_pad_numbers_are_jumpers no)
		(fp_poly
			(pts
				(xy 0.2794 -0.1016) (xy -0.2794 -0.1016) (xy -0.2794 0.9906) (xy 0.2794 0.9906)
			)
			(stroke
				(width 0)
				(type default)
			)
			(fill no)
			(layer "B.CrtYd")
		)
		(fp_line
			(start -0.2794 -0.1016)
			(end 0.2794 -0.1016)
			(stroke
				(width 0.1)
				(type default)
			)
			(layer "B.Fab")
		)
		(fp_line
			(start -0.2794 0.9906)
			(end -0.2794 -0.1016)
			(stroke
				(width 0.1)
				(type default)
			)
			(layer "B.Fab")
		)
		(fp_line
			(start 0.2794 -0.1016)
			(end 0.2794 0.9906)
			(stroke
				(width 0.1)
				(type default)
			)
			(layer "B.Fab")
		)
		(fp_line
			(start 0.2794 0.9906)
			(end -0.2794 0.9906)
			(stroke
				(width 0.1)
				(type default)
			)
			(layer "B.Fab")
		)
		(pad "1" smd rect
			(at 0 0 180)
			(size 0.508 0.508)
			(layers "B.Cu" "B.Mask" "B.Paste")
			(net "P3V3_STBY")
		)
		(pad "2" smd rect
			(at 0 0.889 180)
			(size 0.508 0.508)
			(layers "B.Cu" "B.Mask" "B.Paste")
			(net "PCA9555_A0")
		)
		(zone
			(layer "B.Cu")
			(hatch none 0.5)
			(connect_pads
				(clearance 0)
			)
			(min_thickness 0.25)
			(keepout
				(tracks allowed)
				(vias not_allowed)
				(pads allowed)
				(copperpour not_allowed)
				(footprints allowed)
			)
			(placement
				(enabled no)
				(sheetname "")
			)
			(fill
				(thermal_gap 0.5)
				(thermal_bridge_width 0.5)
				(island_removal_mode 0)
			)
			(polygon
				(pts
					(xy 476.428816 -146.105372) (xy 475.920816 -146.105372) (xy 475.920816 -145.724372) (xy 476.428816 -145.724372)
				)
			)
		)
		(zone
			(layer "B.Cu")
			(hatch none 0.5)
			(connect_pads
				(clearance 0)
			)
			(min_thickness 0.25)
			(keepout
				(tracks not_allowed)
				(vias allowed)
				(pads allowed)
				(copperpour not_allowed)
				(footprints allowed)
			)
			(placement
				(enabled no)
				(sheetname "")
			)
			(fill
				(thermal_gap 0.5)
				(thermal_bridge_width 0.5)
				(island_removal_mode 0)
			)
			(polygon
				(pts
					(xy 476.428816 -145.724372) (xy 475.920816 -145.724372) (xy 475.920816 -146.105372) (xy 476.428816 -146.105372)
				)
			)
		)
	)
	(footprint ""
		(layer "B.Cu")
		(at 20.193 -95.5294)
		(property "Reference" "R9N7"
			(at 0 0 0)
			(layer "B.SilkS")
			(hide yes)
			(effects
				(font
					(size 1.27 1.27)
				)
				(justify mirror)
			)
		)
		(property "Value" ""
			(at 0 0 0)
			(layer "B.Fab")
			(effects
				(font
					(size 1.27 1.27)
				)
				(justify mirror)
			)
		)
		(duplicate_pad_numbers_are_jumpers no)
		(fp_poly
			(pts
				(xy 0.2794 -0.1016) (xy -0.2794 -0.1016) (xy -0.2794 0.9906) (xy 0.2794 0.9906)
			)
			(stroke
				(width 0)
				(type default)
			)
			(fill no)
			(layer "B.CrtYd")
		)
		(fp_line
			(start -0.2794 -0.1016)
			(end 0.2794 -0.1016)
			(stroke
				(width 0.1)
				(type default)
			)
			(layer "B.Fab")
		)
		(fp_line
			(start -0.2794 0.9906)
			(end -0.2794 -0.1016)
			(stroke
				(width 0.1)
				(type default)
			)
			(layer "B.Fab")
		)
		(fp_line
			(start 0.2794 -0.1016)
			(end 0.2794 0.9906)
			(stroke
				(width 0.1)
				(type default)
			)
			(layer "B.Fab")
		)
		(fp_line
			(start 0.2794 0.9906)
			(end -0.2794 0.9906)
			(stroke
				(width 0.1)
				(type default)
			)
			(layer "B.Fab")
		)
		(pad "1" smd rect
			(at 0 0 180)
			(size 0.508 0.508)
			(layers "B.Cu" "B.Mask" "B.Paste")
			(net "VR_PVCCIN_CPU1_XADDR2")
		)
		(pad "2" smd rect
			(at 0 0.889 180)
			(size 0.508 0.508)
			(layers "B.Cu" "B.Mask" "B.Paste")
			(net "GND")
		)
		(zone
			(layer "B.Cu")
			(hatch none 0.5)
			(connect_pads
				(clearance 0)
			)
			(min_thickness 0.25)
			(keepout
				(tracks allowed)
				(vias not_allowed)
				(pads allowed)
				(copperpour not_allowed)
				(footprints allowed)
			)
			(placement
				(enabled no)
				(sheetname "")
			)
			(fill
				(thermal_gap 0.5)
				(thermal_bridge_width 0.5)
				(island_removal_mode 0)
			)
			(polygon
				(pts
					(xy 20.447 -95.2754) (xy 19.939 -95.2754) (xy 19.939 -94.8944) (xy 20.447 -94.8944)
				)
			)
		)
		(zone
			(layer "B.Cu")
			(hatch none 0.5)
			(connect_pads
				(clearance 0)
			)
			(min_thickness 0.25)
			(keepout
				(tracks not_allowed)
				(vias allowed)
				(pads allowed)
				(copperpour not_allowed)
				(footprints allowed)
			)
			(placement
				(enabled no)
				(sheetname "")
			)
			(fill
				(thermal_gap 0.5)
				(thermal_bridge_width 0.5)
				(island_removal_mode 0)
			)
			(polygon
				(pts
					(xy 20.447 -94.8944) (xy 19.939 -94.8944) (xy 19.939 -95.2754) (xy 20.447 -95.2754)
				)
			)
		)
	)
)
